# SCM (Grand Teton) — schematic netlist excerpt (pin names and nets, part order shuffled) for the footprints in the layout excerpt that follows; sources: Cadence DE-HDL packaged netlist, KiCad conversion of 12092022_DA0F0TMDCD0_F0T_Management_Board_D_brd_V3_OCP.brd

R782  Q_RES  0 5% EMPTY  pkg 0402LF  page 17 : A = P1V2_AUX ; B = ADCVREFEXT1
C54  Q_CAP  0.1UF 25V 10% X7R  pkg 0402  page 16 : A = P1V0_STBY_PLAVDD ; B = GND

(kicad_pcb
	(version 20260206)
	(generator "pcbnew")
	(generator_version "10.0")
	(general
		(thickness 1.6)
		(legacy_teardrops no)
	)
	(paper "A4")
	(title_block
		(title "12092022_DA0F0TMDCD0_F0T_Management_Board_D_brd_V3_OCP.brd")
		(comment 1 "Grand Teton / footprints 1247-1248 of 1440")
	)
	(layers
		(0 "F.Cu" signal "TOP")
		(4 "In1.Cu" signal "GND")
		(6 "In2.Cu" signal "IN1")
		(8 "In3.Cu" signal "GND1")
		(10 "In4.Cu" signal "IN2")
		(12 "In5.Cu" signal "VCC")
		(14 "In6.Cu" signal "VCC1")
		(16 "In7.Cu" signal "IN3")
		(18 "In8.Cu" signal "GND2")
		(20 "In9.Cu" signal "IN4")
		(22 "In10.Cu" signal "GND3")
		(2 "B.Cu" signal "BOTTOM")
		(9 "F.Adhes" user "F.Adhesive")
		(11 "B.Adhes" user "B.Adhesive")
		(13 "F.Paste" user "Package Geometry/Pastemask Top")
		(15 "B.Paste" user "Package Geometry/Pastemask Bottom")
		(5 "F.SilkS" user "Ref Des/Silkscreen Top")
		(7 "B.SilkS" user "Ref Des/Silkscreen Bottom")
		(1 "F.Mask" user "Board Geometry/Soldermask Top")
		(3 "B.Mask" user "Board Geometry/Soldermask Bottom")
		(17 "Dwgs.User" user "User.Drawings")
		(19 "Cmts.User" user "User.Comments")
		(21 "Eco1.User" user "User.Eco1")
		(23 "Eco2.User" user "User.Eco2")
		(25 "Edge.Cuts" user "Board Geometry/Outline")
		(27 "Margin" user)
		(31 "F.CrtYd" user "Package Geometry/Place Bound Top")
		(29 "B.CrtYd" user "Package Geometry/Place Bound Bottom")
		(35 "F.Fab" user "Ref Des/Assembly Top")
		(33 "B.Fab" user "Ref Des/Assembly Bottom")
	)
	(footprint ""
		(layer "B.Cu")
		(at 54.675024 -72.842628)
		(property "Reference" "R782"
			(at 0 0 0)
			(layer "B.SilkS")
			(hide yes)
			(effects
				(font
					(size 1.27 1.27)
				)
				(justify mirror)
			)
		)
		(property "Value" ""
			(at 0 0 0)
			(layer "B.Fab")
			(effects
				(font
					(size 1.27 1.27)
				)
				(justify mirror)
			)
		)
		(duplicate_pad_numbers_are_jumpers no)
		(fp_line
			(start -0.7874 -0.4064)
			(end -0.7874 0.4064)
			(stroke
				(width 0.1524)
				(type default)
			)
			(layer "B.SilkS")
		)
		(fp_line
			(start -0.7874 0.4064)
			(end 0.7874 0.4064)
			(stroke
				(width 0.1524)
				(type default)
			)
			(layer "B.SilkS")
		)
		(fp_line
			(start 0.7874 -0.4064)
			(end -0.7874 -0.4064)
			(stroke
				(width 0.1524)
				(type default)
			)
			(layer "B.SilkS")
		)
		(fp_line
			(start 0.7874 0.4064)
			(end 0.7874 -0.4064)
			(stroke
				(width 0.1524)
				(type default)
			)
			(layer "B.SilkS")
		)
		(fp_line
			(start -0.67945 -0.3048)
			(end -0.67945 0.3048)
			(stroke
				(width 0.1)
				(type default)
			)
			(layer "B.Fab")
		)
		(fp_line
			(start -0.67945 0.3048)
			(end -0.120396 0.3048)
			(stroke
				(width 0.1)
				(type default)
			)
			(layer "B.Fab")
		)
		(fp_line
			(start -0.12065 -0.3048)
			(end -0.67945 -0.3048)
			(stroke
				(width 0.1)
				(type default)
			)
			(layer "B.Fab")
		)
		(fp_line
			(start -0.12065 -0.2794)
			(end -0.12065 -0.3048)
			(stroke
				(width 0.1)
				(type default)
			)
			(layer "B.Fab")
		)
		(fp_line
			(start -0.120396 0.2794)
			(end 0.12065 0.2794)
			(stroke
				(width 0.1)
				(type default)
			)
			(layer "B.Fab")
		)
		(fp_line
			(start -0.120396 0.3048)
			(end -0.120396 0.2794)
			(stroke
				(width 0.1)
				(type default)
			)
			(layer "B.Fab")
		)
		(fp_line
			(start 0.12065 -0.305054)
			(end 0.12065 -0.2794)
			(stroke
				(width 0.1)
				(type default)
			)
			(layer "B.Fab")
		)
		(fp_line
			(start 0.12065 -0.2794)
			(end -0.12065 -0.2794)
			(stroke
				(width 0.1)
				(type default)
			)
			(layer "B.Fab")
		)
		(fp_line
			(start 0.12065 0.2794)
			(end 0.12065 0.3048)
			(stroke
				(width 0.1)
				(type default)
			)
			(layer "B.Fab")
		)
		(fp_line
			(start 0.12065 0.3048)
			(end 0.67945 0.3048)
			(stroke
				(width 0.1)
				(type default)
			)
			(layer "B.Fab")
		)
		(fp_line
			(start 0.67945 -0.305054)
			(end 0.12065 -0.305054)
			(stroke
				(width 0.1)
				(type default)
			)
			(layer "B.Fab")
		)
		(fp_line
			(start 0.67945 0.3048)
			(end 0.67945 -0.305054)
			(stroke
				(width 0.1)
				(type default)
			)
			(layer "B.Fab")
		)
		(pad "1" smd circle
			(at 0.40005 0 180)
			(size 0 0)
			(layers "B.Cu" "B.Mask" "B.Paste")
			(net "P1V2_AUX")
		)
		(pad "2" smd circle
			(at -0.40005 0 180)
			(size 0 0)
			(layers "B.Cu" "B.Mask" "B.Paste")
			(net "ADCVREFEXT1")
		)
	)
	(footprint ""
		(layer "B.Cu")
		(at 58.702194 -44.406312 -90)
		(property "Reference" "C54"
			(at 0 0 90)
			(layer "B.SilkS")
			(hide yes)
			(effects
				(font
					(size 1.27 1.27)
				)
				(justify mirror)
			)
		)
		(property "Value" ""
			(at 0 0 90)
			(layer "B.Fab")
			(effects
				(font
					(size 1.27 1.27)
				)
				(justify mirror)
			)
		)
		(duplicate_pad_numbers_are_jumpers no)
		(fp_line
			(start -0.7874 0.4064)
			(end 0.7874 0.4064)
			(stroke
				(width 0.1524)
				(type default)
			)
			(layer "B.SilkS")
		)
		(fp_line
			(start 0.7874 0.4064)
			(end 0.7874 -0.4064)
			(stroke
				(width 0.1524)
				(type default)
			)
			(layer "B.SilkS")
		)
		(fp_line
			(start -0.7874 -0.4064)
			(end -0.7874 0.4064)
			(stroke
				(width 0.1524)
				(type default)
			)
			(layer "B.SilkS")
		)
		(fp_line
			(start 0.7874 -0.4064)
			(end -0.7874 -0.4064)
			(stroke
				(width 0.1524)
				(type default)
			)
			(layer "B.SilkS")
		)
		(fp_line
			(start -0.67945 0.3048)
			(end -0.120396 0.3048)
			(stroke
				(width 0.1)
				(type default)
			)
			(layer "B.Fab")
		)
		(fp_line
			(start -0.120396 0.3048)
			(end -0.120396 0.2794)
			(stroke
				(width 0.1)
				(type default)
			)
			(layer "B.Fab")
		)
		(fp_line
			(start 0.12065 0.3048)
			(end 0.67945 0.3048)
			(stroke
				(width 0.1)
				(type default)
			)
			(layer "B.Fab")
		)
		(fp_line
			(start 0.67945 0.3048)
			(end 0.67945 -0.305054)
			(stroke
				(width 0.1)
				(type default)
			)
			(layer "B.Fab")
		)
		(fp_line
			(start -0.120396 0.2794)
			(end 0.12065 0.2794)
			(stroke
				(width 0.1)
				(type default)
			)
			(layer "B.Fab")
		)
		(fp_line
			(start 0.12065 0.2794)
			(end 0.12065 0.3048)
			(stroke
				(width 0.1)
				(type default)
			)
			(layer "B.Fab")
		)
		(fp_line
			(start -0.12065 -0.2794)
			(end -0.12065 -0.3048)
			(stroke
				(width 0.1)
				(type default)
			)
			(layer "B.Fab")
		)
		(fp_line
			(start 0.12065 -0.2794)
			(end -0.12065 -0.2794)
			(stroke
				(width 0.1)
				(type default)
			)
			(layer "B.Fab")
		)
		(fp_line
			(start -0.67945 -0.3048)
			(end -0.67945 0.3048)
			(stroke
				(width 0.1)
				(type default)
			)
			(layer "B.Fab")
		)
		(fp_line
			(start -0.12065 -0.3048)
			(end -0.67945 -0.3048)
			(stroke
				(width 0.1)
				(type default)
			)
			(layer "B.Fab")
		)
		(fp_line
			(start 0.12065 -0.305054)
			(end 0.12065 -0.2794)
			(stroke
				(width 0.1)
				(type default)
			)
			(layer "B.Fab")
		)
		(fp_line
			(start 0.67945 -0.305054)
			(end 0.12065 -0.305054)
			(stroke
				(width 0.1)
				(type default)
			)
			(layer "B.Fab")
		)
		(pad "1" smd circle
			(at 0.40005 0 90)
			(size 0 0)
			(layers "B.Cu" "B.Mask" "B.Paste")
			(net "P1V0_STBY_PLAVDD")
		)
		(pad "2" smd circle
			(at -0.40005 0 90)
			(size 0 0)
			(layers "B.Cu" "B.Mask" "B.Paste")
			(net "GND")
		)
	)
)
